(kicad_pcb
	(version 20260206)
	(generator "pcbnew")
	(generator_version "10.0")
	(general
		(thickness 1.6)
		(legacy_teardrops no)
	)
	(paper "A4")
	(title_block
		(title "Wiwynn_Tioga_Pass_MB.brd")
		(comment 1 "Tioga Pass / footprints 2395-2402 of 4770")
	)
	(layers
		(0 "F.Cu" signal "TOP")
		(4 "In1.Cu" signal "L2GND")
		(6 "In2.Cu" signal "L3")
		(8 "In3.Cu" signal "L4GND")
		(10 "In4.Cu" signal "L5")
		(12 "In5.Cu" signal "L6GND")
		(14 "In6.Cu" signal "L7VCC")
		(16 "In7.Cu" signal "L8VCC")
		(18 "In8.Cu" signal "L9GND")
		(20 "In9.Cu" signal "L10")
		(22 "In10.Cu" signal "L11GND")
		(24 "In11.Cu" signal "L12")
		(26 "In12.Cu" signal "L13GND")
		(2 "B.Cu" signal "BOTTOM")
		(9 "F.Adhes" user "F.Adhesive")
		(11 "B.Adhes" user "B.Adhesive")
		(13 "F.Paste" user "Package Geometry/Pastemask Top")
		(15 "B.Paste" user "Package Geometry/Pastemask Bottom")
		(5 "F.SilkS" user "Ref Des/Silkscreen Top")
		(7 "B.SilkS" user "Ref Des/Silkscreen Bottom")
		(1 "F.Mask" user "Board Geometry/Soldermask Top")
		(3 "B.Mask" user "Board Geometry/Soldermask Bottom")
		(17 "Dwgs.User" user "User.Drawings")
		(19 "Cmts.User" user "User.Comments")
		(21 "Eco1.User" user "User.Eco1")
		(23 "Eco2.User" user "User.Eco2")
		(25 "Edge.Cuts" user "Board Geometry/Outline")
		(27 "Margin" user)
		(31 "F.CrtYd" user "Package Geometry/Place Bound Top")
		(29 "B.CrtYd" user "Package Geometry/Place Bound Bottom")
		(35 "F.Fab" user "Ref Des/Assembly Top")
		(33 "B.Fab" user "Ref Des/Assembly Bottom")
	)
	(footprint ""
		(layer "B.Cu")
		(at 410.097986 -11.857736 -90)
		(property "Reference" "C2R12"
			(at 0 0 90)
			(layer "B.SilkS")
			(hide yes)
			(effects
				(font
					(size 1.27 1.27)
				)
				(justify mirror)
			)
		)
		(property "Value" ""
			(at 0 0 90)
			(layer "B.Fab")
			(effects
				(font
					(size 1.27 1.27)
				)
				(justify mirror)
			)
		)
		(duplicate_pad_numbers_are_jumpers no)
		(fp_poly
			(pts
				(xy -0.3048 -0.1016) (xy -0.3048 0.9906) (xy 0.3048 0.9906) (xy 0.3048 -0.1016)
			)
			(stroke
				(width 0)
				(type default)
			)
			(fill no)
			(layer "B.CrtYd")
		)
		(fp_line
			(start -0.3048 0.9906)
			(end -0.3048 -0.1016)
			(stroke
				(width 0.1)
				(type default)
			)
			(layer "B.Fab")
		)
		(fp_line
			(start 0.3048 0.9906)
			(end -0.3048 0.9906)
			(stroke
				(width 0.1)
				(type default)
			)
			(layer "B.Fab")
		)
		(fp_line
			(start -0.3048 -0.1016)
			(end 0.3048 -0.1016)
			(stroke
				(width 0.1)
				(type default)
			)
			(layer "B.Fab")
		)
		(fp_line
			(start 0.3048 -0.1016)
			(end 0.3048 0.9906)
			(stroke
				(width 0.1)
				(type default)
			)
			(layer "B.Fab")
		)
		(pad "1" smd rect
			(at 0 0 90)
			(size 0.508 0.508)
			(layers "B.Cu" "B.Mask" "B.Paste")
			(net "FP_NMI_BTN_OUT_N")
		)
		(pad "2" smd rect
			(at 0 0.889 90)
			(size 0.508 0.508)
			(layers "B.Cu" "B.Mask" "B.Paste")
			(net "GND")
		)
		(zone
			(layer "B.Cu")
			(hatch none 0.5)
			(connect_pads
				(clearance 0)
			)
			(min_thickness 0.25)
			(keepout
				(tracks not_allowed)
				(vias allowed)
				(pads allowed)
				(copperpour not_allowed)
				(footprints allowed)
			)
			(placement
				(enabled no)
				(sheetname "")
			)
			(fill
				(thermal_gap 0.5)
				(thermal_bridge_width 0.5)
				(island_removal_mode 0)
			)
			(polygon
				(pts
					(xy 409.462986 -11.603736) (xy 409.462986 -12.111736) (xy 409.843986 -12.111736) (xy 409.843986 -11.603736)
				)
			)
		)
		(zone
			(layer "B.Cu")
			(hatch none 0.5)
			(connect_pads
				(clearance 0)
			)
			(min_thickness 0.25)
			(keepout
				(tracks allowed)
				(vias not_allowed)
				(pads allowed)
				(copperpour not_allowed)
				(footprints allowed)
			)
			(placement
				(enabled no)
				(sheetname "")
			)
			(fill
				(thermal_gap 0.5)
				(thermal_bridge_width 0.5)
				(island_removal_mode 0)
			)
			(polygon
				(pts
					(xy 409.843986 -11.603736) (xy 409.843986 -12.111736) (xy 409.462986 -12.111736) (xy 409.462986 -11.603736)
				)
			)
		)
	)
	(footprint ""
		(layer "B.Cu")
		(at 446.381632 -33.5915 90)
		(property "Reference" "R25W2"
			(at 0 0 90)
			(layer "B.SilkS")
			(hide yes)
			(effects
				(font
					(size 1.27 1.27)
				)
				(justify mirror)
			)
		)
		(property "Value" "*"
			(at -0.064008 -4.108196 90)
			(unlocked yes)
			(layer "B.Fab")
			(hide yes)
			(effects
				(font
					(size 1.27 1.016)
					(thickness 0.1524)
				)
				(justify mirror)
			)
		)
		(property "Device Type" "120R2F-GP_RCL_GP-120R2F-GP,64.A"
			(at -0.064008 -5.632196 90)
			(unlocked yes)
			(layer "B.Fab")
			(hide yes)
			(effects
				(font
					(size 1.27 1.016)
					(thickness 0.1524)
				)
				(justify mirror)
			)
		)
		(duplicate_pad_numbers_are_jumpers no)
		(fp_line
			(start 0.508 -0.9398)
			(end 0.508 0.9398)
			(stroke
				(width 0.1524)
				(type default)
			)
			(layer "B.SilkS")
		)
		(fp_line
			(start -0.508 -0.9398)
			(end 0.508 -0.9398)
			(stroke
				(width 0.1524)
				(type default)
			)
			(layer "B.SilkS")
		)
		(fp_rect
			(start 0.508 0.9398)
			(end -0.508 -0.9398)
			(stroke
				(width 0)
				(type default)
			)
			(fill no)
			(layer "B.CrtYd")
		)
		(fp_rect
			(start 0.508 0.9398)
			(end -0.508 -0.9398)
			(stroke
				(width 0)
				(type default)
			)
			(fill no)
			(layer "B.Fab")
		)
		(pad "1" smd custom
			(at 0 -0.4445 270)
			(size 0.1397 0.1397)
			(layers "B.Cu" "B.Mask" "B.Paste")
			(net "GND")
			(options
				(clearance outline)
				(anchor circle)
			)
			(primitives
				(gr_poly
					(pts
						(arc
							(start -0.1778 0.2794)
							(mid -0.249642 0.249642)
							(end -0.2794 0.1778)
						)
						(arc
							(start -0.2794 -0.1778)
							(mid -0.249642 -0.249642)
							(end -0.1778 -0.2794)
						)
						(arc
							(start 0.1778 -0.2794)
							(mid 0.249642 -0.249642)
							(end 0.2794 -0.1778)
						)
						(arc
							(start 0.2794 0.1778)
							(mid 0.249642 0.249642)
							(end 0.1778 0.2794)
						)
					)
					(width 0)
					(fill yes)
				)
			)
		)
		(pad "2" smd custom
			(at 0 0.4445 270)
			(size 0.1397 0.1397)
			(layers "B.Cu" "B.Mask" "B.Paste")
			(net "BMC_M_ODT")
			(options
				(clearance outline)
				(anchor circle)
			)
			(primitives
				(gr_poly
					(pts
						(arc
							(start -0.1778 0.2794)
							(mid -0.249642 0.249642)
							(end -0.2794 0.1778)
						)
						(arc
							(start -0.2794 -0.1778)
							(mid -0.249642 -0.249642)
							(end -0.1778 -0.2794)
						)
						(arc
							(start 0.1778 -0.2794)
							(mid 0.249642 -0.249642)
							(end 0.2794 -0.1778)
						)
						(arc
							(start 0.2794 0.1778)
							(mid 0.249642 0.249642)
							(end 0.1778 0.2794)
						)
					)
					(width 0)
					(fill yes)
				)
			)
		)
	)
	(footprint ""
		(layer "B.Cu")
		(at 32.832802 -82.681064 90)
		(property "Reference" "C9P1"
			(at 0 0 90)
			(layer "B.SilkS")
			(hide yes)
			(effects
				(font
					(size 1.27 1.27)
				)
				(justify mirror)
			)
		)
		(property "Value" ""
			(at 0 0 90)
			(layer "B.Fab")
			(effects
				(font
					(size 1.27 1.27)
				)
				(justify mirror)
			)
		)
		(duplicate_pad_numbers_are_jumpers no)
		(fp_poly
			(pts
				(xy 0.7239 -0.2159) (xy -0.7239 -0.2159) (xy -0.7239 1.9939) (xy 0.7239 1.9939)
			)
			(stroke
				(width 0)
				(type default)
			)
			(fill no)
			(layer "B.CrtYd")
		)
		(fp_line
			(start 0.7239 -0.2159)
			(end 0.7239 1.9939)
			(stroke
				(width 0.1)
				(type default)
			)
			(layer "B.Fab")
		)
		(fp_line
			(start -0.7239 -0.2159)
			(end 0.7239 -0.2159)
			(stroke
				(width 0.1)
				(type default)
			)
			(layer "B.Fab")
		)
		(fp_line
			(start 0.7239 1.9939)
			(end -0.7239 1.9939)
			(stroke
				(width 0.1)
				(type default)
			)
			(layer "B.Fab")
		)
		(fp_line
			(start -0.7239 1.9939)
			(end -0.7239 -0.2159)
			(stroke
				(width 0.1)
				(type default)
			)
			(layer "B.Fab")
		)
		(pad "1" smd rect
			(at 0 0 270)
			(size 1.27 1.016)
			(layers "B.Cu" "B.Mask" "B.Paste")
			(net "VR_FET_SW_P12V_STBY_PVCCIN_CPU1")
		)
		(pad "2" smd rect
			(at 0 1.778 270)
			(size 1.27 1.016)
			(layers "B.Cu" "B.Mask" "B.Paste")
			(net "GND")
		)
		(zone
			(layer "B.Cu")
			(hatch none 0.5)
			(connect_pads
				(clearance 0)
			)
			(min_thickness 0.25)
			(keepout
				(tracks not_allowed)
				(vias allowed)
				(pads allowed)
				(copperpour not_allowed)
				(footprints allowed)
			)
			(placement
				(enabled no)
				(sheetname "")
			)
			(fill
				(thermal_gap 0.5)
				(thermal_bridge_width 0.5)
				(island_removal_mode 0)
			)
			(polygon
				(pts
					(xy 33.340802 -83.316064) (xy 33.340802 -82.046064) (xy 34.102802 -82.046064) (xy 34.102802 -83.316064)
				)
			)
		)
	)
	(footprint ""
		(layer "B.Cu")
		(at 104.5591 -3.3528 90)
		(property "Reference" "C5G90"
			(at -1.14681 0.76708 180)
			(unlocked yes)
			(layer "B.SilkS")
			(effects
				(font
					(size 0.7874 0.5842)
					(thickness 0.1524)
				)
				(justify mirror)
			)
		)
		(property "Value" ""
			(at 0 0 90)
			(layer "B.Fab")
			(effects
				(font
					(size 1.27 1.27)
				)
				(justify mirror)
			)
		)
		(duplicate_pad_numbers_are_jumpers no)
		(fp_rect
			(start -0.4953 -0.2032)
			(end 0.4953 1.6002)
			(stroke
				(width 0)
				(type default)
			)
			(fill no)
			(layer "B.CrtYd")
		)
		(fp_line
			(start 0.4953 -0.2032)
			(end -0.4953 -0.2032)
			(stroke
				(width 0.1)
				(type default)
			)
			(layer "B.Fab")
		)
		(fp_line
			(start -0.4953 -0.2032)
			(end -0.4953 1.6002)
			(stroke
				(width 0.1)
				(type default)
			)
			(layer "B.Fab")
		)
		(fp_line
			(start 0.4953 1.6002)
			(end 0.4953 -0.2032)
			(stroke
				(width 0.1)
				(type default)
			)
			(layer "B.Fab")
		)
		(fp_line
			(start -0.4953 1.6002)
			(end 0.4953 1.6002)
			(stroke
				(width 0.1)
				(type default)
			)
			(layer "B.Fab")
		)
		(pad "1" smd rect
			(at 0 0 270)
			(size 0.762 0.889)
			(layers "B.Cu" "B.Mask" "B.Paste")
			(net "PVDDQ_GHJ")
		)
		(pad "2" smd rect
			(at 0 1.397 270)
			(size 0.762 0.889)
			(layers "B.Cu" "B.Mask" "B.Paste")
			(net "GND")
		)
		(zone
			(layer "B.Cu")
			(hatch none 0.5)
			(connect_pads
				(clearance 0)
			)
			(min_thickness 0.25)
			(keepout
				(tracks not_allowed)
				(vias allowed)
				(pads allowed)
				(copperpour not_allowed)
				(footprints allowed)
			)
			(placement
				(enabled no)
				(sheetname "")
			)
			(fill
				(thermal_gap 0.5)
				(thermal_bridge_width 0.5)
				(island_removal_mode 0)
			)
			(polygon
				(pts
					(xy 105.0036 -2.9718) (xy 105.5116 -2.9718) (xy 105.5116 -3.7338) (xy 105.0036 -3.7338)
				)
			)
		)
	)
	(footprint ""
		(layer "B.Cu")
		(at 97.206054 -73.51014)
		(property "Reference" "C8P27"
			(at 0 0 0)
			(layer "B.SilkS")
			(hide yes)
			(effects
				(font
					(size 1.27 1.27)
				)
				(justify mirror)
			)
		)
		(property "Value" ""
			(at 0 0 0)
			(layer "B.Fab")
			(effects
				(font
					(size 1.27 1.27)
				)
				(justify mirror)
			)
		)
		(duplicate_pad_numbers_are_jumpers no)
		(fp_poly
			(pts
				(xy 0.7239 -0.2159) (xy -0.7239 -0.2159) (xy -0.7239 1.9939) (xy 0.7239 1.9939)
			)
			(stroke
				(width 0)
				(type default)
			)
			(fill no)
			(layer "B.CrtYd")
		)
		(fp_line
			(start -0.7239 -0.2159)
			(end 0.7239 -0.2159)
			(stroke
				(width 0.1)
				(type default)
			)
			(layer "B.Fab")
		)
		(fp_line
			(start -0.7239 1.9939)
			(end -0.7239 -0.2159)
			(stroke
				(width 0.1)
				(type default)
			)
			(layer "B.Fab")
		)
		(fp_line
			(start 0.7239 -0.2159)
			(end 0.7239 1.9939)
			(stroke
				(width 0.1)
				(type default)
			)
			(layer "B.Fab")
		)
		(fp_line
			(start 0.7239 1.9939)
			(end -0.7239 1.9939)
			(stroke
				(width 0.1)
				(type default)
			)
			(layer "B.Fab")
		)
		(pad "1" smd rect
			(at 0 0 180)
			(size 1.27 1.016)
			(layers "B.Cu" "B.Mask" "B.Paste")
			(net "PVCCIN_CPU1")
		)
		(pad "2" smd rect
			(at 0 1.778 180)
			(size 1.27 1.016)
			(layers "B.Cu" "B.Mask" "B.Paste")
			(net "GND")
		)
		(zone
			(layer "B.Cu")
			(hatch none 0.5)
			(connect_pads
				(clearance 0)
			)
			(min_thickness 0.25)
			(keepout
				(tracks not_allowed)
				(vias allowed)
				(pads allowed)
				(copperpour not_allowed)
				(footprints allowed)
			)
			(placement
				(enabled no)
				(sheetname "")
			)
			(fill
				(thermal_gap 0.5)
				(thermal_bridge_width 0.5)
				(island_removal_mode 0)
			)
			(polygon
				(pts
					(xy 97.841054 -73.00214) (xy 96.571054 -73.00214) (xy 96.571054 -72.24014) (xy 97.841054 -72.24014)
				)
			)
		)
	)
	(footprint ""
		(layer "B.Cu")
		(at 482.854 -32.512 180)
		(property "Reference" "C2T28"
			(at 0 0 0)
			(layer "B.SilkS")
			(hide yes)
			(effects
				(font
					(size 1.27 1.27)
				)
				(justify mirror)
			)
		)
		(property "Value" ""
			(at 0 0 0)
			(layer "B.Fab")
			(effects
				(font
					(size 1.27 1.27)
				)
				(justify mirror)
			)
		)
		(duplicate_pad_numbers_are_jumpers no)
		(fp_poly
			(pts
				(xy -0.3048 -0.1016) (xy -0.3048 0.9906) (xy 0.3048 0.9906) (xy 0.3048 -0.1016)
			)
			(stroke
				(width 0)
				(type default)
			)
			(fill no)
			(layer "B.CrtYd")
		)
		(fp_line
			(start 0.3048 0.9906)
			(end -0.3048 0.9906)
			(stroke
				(width 0.1)
				(type default)
			)
			(layer "B.Fab")
		)
		(fp_line
			(start 0.3048 -0.1016)
			(end 0.3048 0.9906)
			(stroke
				(width 0.1)
				(type default)
			)
			(layer "B.Fab")
		)
		(fp_line
			(start -0.3048 0.9906)
			(end -0.3048 -0.1016)
			(stroke
				(width 0.1)
				(type default)
			)
			(layer "B.Fab")
		)
		(fp_line
			(start -0.3048 -0.1016)
			(end 0.3048 -0.1016)
			(stroke
				(width 0.1)
				(type default)
			)
			(layer "B.Fab")
		)
		(pad "1" smd rect
			(at 0 0)
			(size 0.508 0.508)
			(layers "B.Cu" "B.Mask" "B.Paste")
			(net "P3V3_STBY")
		)
		(pad "2" smd rect
			(at 0 0.889)
			(size 0.508 0.508)
			(layers "B.Cu" "B.Mask" "B.Paste")
			(net "GND")
		)
		(zone
			(layer "B.Cu")
			(hatch none 0.5)
			(connect_pads
				(clearance 0)
			)
			(min_thickness 0.25)
			(keepout
				(tracks not_allowed)
				(vias allowed)
				(pads allowed)
				(copperpour not_allowed)
				(footprints allowed)
			)
			(placement
				(enabled no)
				(sheetname "")
			)
			(fill
				(thermal_gap 0.5)
				(thermal_bridge_width 0.5)
				(island_removal_mode 0)
			)
			(polygon
				(pts
					(xy 482.6 -33.147) (xy 483.108 -33.147) (xy 483.108 -32.766) (xy 482.6 -32.766)
				)
			)
		)
		(zone
			(layer "B.Cu")
			(hatch none 0.5)
			(connect_pads
				(clearance 0)
			)
			(min_thickness 0.25)
			(keepout
				(tracks allowed)
				(vias not_allowed)
				(pads allowed)
				(copperpour not_allowed)
				(footprints allowed)
			)
			(placement
				(enabled no)
				(sheetname "")
			)
			(fill
				(thermal_gap 0.5)
				(thermal_bridge_width 0.5)
				(island_removal_mode 0)
			)
			(polygon
				(pts
					(xy 482.6 -32.766) (xy 483.108 -32.766) (xy 483.108 -33.147) (xy 482.6 -33.147)
				)
			)
		)
	)
	(footprint ""
		(layer "B.Cu")
		(at 27.0764 -77.089 180)
		(property "Reference" "R9P20"
			(at 0 0 0)
			(layer "B.SilkS")
			(hide yes)
			(effects
				(font
					(size 1.27 1.27)
				)
				(justify mirror)
			)
		)
		(property "Value" ""
			(at 0 0 0)
			(layer "B.Fab")
			(effects
				(font
					(size 1.27 1.27)
				)
				(justify mirror)
			)
		)
		(duplicate_pad_numbers_are_jumpers no)
		(fp_poly
			(pts
				(xy 0.2794 -0.1016) (xy -0.2794 -0.1016) (xy -0.2794 0.9906) (xy 0.2794 0.9906)
			)
			(stroke
				(width 0)
				(type default)
			)
			(fill no)
			(layer "B.CrtYd")
		)
		(fp_line
			(start 0.2794 0.9906)
			(end -0.2794 0.9906)
			(stroke
				(width 0.1)
				(type default)
			)
			(layer "B.Fab")
		)
		(fp_line
			(start 0.2794 -0.1016)
			(end 0.2794 0.9906)
			(stroke
				(width 0.1)
				(type default)
			)
			(layer "B.Fab")
		)
		(fp_line
			(start -0.2794 0.9906)
			(end -0.2794 -0.1016)
			(stroke
				(width 0.1)
				(type default)
			)
			(layer "B.Fab")
		)
		(fp_line
			(start -0.2794 -0.1016)
			(end 0.2794 -0.1016)
			(stroke
				(width 0.1)
				(type default)
			)
			(layer "B.Fab")
		)
		(pad "1" smd rect
			(at 0 0)
			(size 0.508 0.508)
			(layers "B.Cu" "B.Mask" "B.Paste")
			(net "P3V3_STBY")
		)
		(pad "2" smd rect
			(at 0 0.889)
			(size 0.508 0.508)
			(layers "B.Cu" "B.Mask" "B.Paste")
			(net "FM_HSC_TIMER_EXP_N")
		)
		(zone
			(layer "B.Cu")
			(hatch none 0.5)
			(connect_pads
				(clearance 0)
			)
			(min_thickness 0.25)
			(keepout
				(tracks not_allowed)
				(vias allowed)
				(pads allowed)
				(copperpour not_allowed)
				(footprints allowed)
			)
			(placement
				(enabled no)
				(sheetname "")
			)
			(fill
				(thermal_gap 0.5)
				(thermal_bridge_width 0.5)
				(island_removal_mode 0)
			)
			(polygon
				(pts
					(xy 26.8224 -77.724) (xy 27.3304 -77.724) (xy 27.3304 -77.343) (xy 26.8224 -77.343)
				)
			)
		)
		(zone
			(layer "B.Cu")
			(hatch none 0.5)
			(connect_pads
				(clearance 0)
			)
			(min_thickness 0.25)
			(keepout
				(tracks allowed)
				(vias not_allowed)
				(pads allowed)
				(copperpour not_allowed)
				(footprints allowed)
			)
			(placement
				(enabled no)
				(sheetname "")
			)
			(fill
				(thermal_gap 0.5)
				(thermal_bridge_width 0.5)
				(island_removal_mode 0)
			)
			(polygon
				(pts
					(xy 26.8224 -77.343) (xy 27.3304 -77.343) (xy 27.3304 -77.724) (xy 26.8224 -77.724)
				)
			)
		)
	)
	(footprint ""
		(layer "B.Cu")
		(at 453.6948 -147.5486 90)
		(property "Reference" "R9A11"
			(at 0 0 90)
			(layer "B.SilkS")
			(hide yes)
			(effects
				(font
					(size 1.27 1.27)
				)
				(justify mirror)
			)
		)
		(property "Value" ""
			(at 0 0 90)
			(layer "B.Fab")
			(effects
				(font
					(size 1.27 1.27)
				)
				(justify mirror)
			)
		)
		(duplicate_pad_numbers_are_jumpers no)
		(fp_poly
			(pts
				(xy 0.2794 -0.1016) (xy -0.2794 -0.1016) (xy -0.2794 0.9906) (xy 0.2794 0.9906)
			)
			(stroke
				(width 0)
				(type default)
			)
			(fill no)
			(layer "B.CrtYd")
		)
		(fp_line
			(start 0.2794 -0.1016)
			(end 0.2794 0.9906)
			(stroke
				(width 0.1)
				(type default)
			)
			(layer "B.Fab")
		)
		(fp_line
			(start -0.2794 -0.1016)
			(end 0.2794 -0.1016)
			(stroke
				(width 0.1)
				(type default)
			)
			(layer "B.Fab")
		)
		(fp_line
			(start 0.2794 0.9906)
			(end -0.2794 0.9906)
			(stroke
				(width 0.1)
				(type default)
			)
			(layer "B.Fab")
		)
		(fp_line
			(start -0.2794 0.9906)
			(end -0.2794 -0.1016)
			(stroke
				(width 0.1)
				(type default)
			)
			(layer "B.Fab")
		)
		(pad "1" smd rect
			(at 0 0 270)
			(size 0.508 0.508)
			(layers "B.Cu" "B.Mask" "B.Paste")
			(net "P1V05_PCH_STBY")
		)
		(pad "2" smd rect
			(at 0 0.889 270)
			(size 0.508 0.508)
			(layers "B.Cu" "B.Mask" "B.Paste")
			(net "XDP_TDO")
		)
		(zone
			(layer "B.Cu")
			(hatch none 0.5)
			(connect_pads
				(clearance 0)
			)
			(min_thickness 0.25)
			(keepout
				(tracks allowed)
				(vias not_allowed)
				(pads allowed)
				(copperpour not_allowed)
				(footprints allowed)
			)
			(placement
				(enabled no)
				(sheetname "")
			)
			(fill
				(thermal_gap 0.5)
				(thermal_bridge_width 0.5)
				(island_removal_mode 0)
			)
			(polygon
				(pts
					(xy 453.9488 -147.8026) (xy 453.9488 -147.2946) (xy 454.3298 -147.2946) (xy 454.3298 -147.8026)
				)
			)
		)
		(zone
			(layer "B.Cu")
			(hatch none 0.5)
			(connect_pads
				(clearance 0)
			)
			(min_thickness 0.25)
			(keepout
				(tracks not_allowed)
				(vias allowed)
				(pads allowed)
				(copperpour not_allowed)
				(footprints allowed)
			)
			(placement
				(enabled no)
				(sheetname "")
			)
			(fill
				(thermal_gap 0.5)
				(thermal_bridge_width 0.5)
				(island_removal_mode 0)
			)
			(polygon
				(pts
					(xy 454.3298 -147.8026) (xy 454.3298 -147.2946) (xy 453.9488 -147.2946) (xy 453.9488 -147.8026)
				)
			)
		)
	)
)
